Full redundant data path to each HDD
This high-density storage system is designed 
with redundant controllers to provide full 
redundant data path to each HDD.
Hot-plug and redundant cooling for high 
availability
Wiwynn ST7110-30A supports high 
availability with hot-plug hard drives and 
redundant cooling.
High-density HDD storage system
With an impressive storage capacity of 30 
SAS hard drives in a 2U chassis, Wiwynn 
ST7110-30A stands out from other JBOD 
storage systems as having the highest 
storage density in the industry.
Tool-less design for easy maintenance
Wiwynn ST7110-30A’s drawer-like innovative 
design allows housing for 15 hard drives in 
each node or a total of 30 hard drives for the 
whole system. Its creative and practical 
design allows users to upgrade, maintain 
and replace with ease.
Hot-plug HDDs
Without interrupting ongoing tasks or 
applications, the hot-plug hard drives on 
Wiwynn ST7110-30A can be  swapped 
immediately when drive failures occur, 
saving lots of time and eﬀort for 
maintenance and repair.
www.wiwynn.com
Unique and high-capacity 
storage system with high 
availability and /f_lexibility
WiRack21 Storage
Wiwynn ST7110-30A 


8F, 90, Sec. 1, Xintai 5th Rd., Xizhi Dist., New Taipei City, 22102,Taiwan, R.O.C.
Telephone: 886-2-6615-8888       Email: <email>
Copyright © 2012 by Wiwynn Corporation.
All rights reserved. No part of this publication may be reproduced, transmitted, transcribed, stored in a retrieval system, or translated into any language or computer language, in any form or by any means, electronic, 
mechanical, magnetic, optical, chemical, manual or otherwise, without the prior written permission of Wiwynn Corporation.
Storage and I/O
Expander SAS6G Expander
Storage Thirty 3.5" hot-plug drive bays (/f_ifteen per tray):  
 hSAS/SATA SSD with 2.5" drive cage
h SAS HDD (10K rpm) 
 hNearline SAS HDD (7.2K rpm)
h SATA HDD (7.2K rpm) 
 Two INT mini-SAS 6G (SASx4) ports
 One EXT mini-SAS 6G (SASx4) port
Remote Management SES, SMP
Power Supply, Physical and Packaging Speci/f_ications
Power Supply Centralized 12V DC bus bar
Power Consumption 300W (Idle); 400W (Max) 
Form Factor and Dimensions 2 OU rack; 93.5 (H) * 536 (W) * 795 (D) (mm)
Weight  38 kg ~ 55 kg 
Model : Wiwynn ST7110-30A
Wiwynn, a spin-oﬀ from Wistron group, is a 
fast-growing cloud infrastructure provider developing 
high-density computing and storage products for 
leading data centers. In addition, Wiwynn provides 
enterprises with fast-deployment, reliable and 
ready-to-use cloud appliances to accelerate the 
transformation of cloud infrastructure.
